(kicad_pcb
	(version 20260206)
	(generator "pcbnew")
	(generator_version "10.0")
	(general
		(thickness 1.6)
		(legacy_teardrops no)
	)
	(paper "A4")
	(title_block
		(title "12092022_DA0F0TFB6D0_F0T_FAN_BOARD_MP5048_D_brd_v02_OCP.brd")
		(comment 1 "Grand Teton / footprints 924-924 of 924")
	)
	(layers
		(0 "F.Cu" signal "TOP")
		(4 "In1.Cu" signal "GND")
		(6 "In2.Cu" signal "IN1")
		(8 "In3.Cu" signal "IN2")
		(10 "In4.Cu" signal "GND1")
		(2 "B.Cu" signal "BOTTOM")
		(9 "F.Adhes" user "F.Adhesive")
		(11 "B.Adhes" user "B.Adhesive")
		(13 "F.Paste" user "Package Geometry/Pastemask Top")
		(15 "B.Paste" user "Package Geometry/Pastemask Bottom")
		(5 "F.SilkS" user "Ref Des/Silkscreen Top")
		(7 "B.SilkS" user "Ref Des/Silkscreen Bottom")
		(1 "F.Mask" user "Board Geometry/Soldermask Top")
		(3 "B.Mask" user "Board Geometry/Soldermask Bottom")
		(17 "Dwgs.User" user "User.Drawings")
		(19 "Cmts.User" user "User.Comments")
		(21 "Eco1.User" user "User.Eco1")
		(23 "Eco2.User" user "User.Eco2")
		(25 "Edge.Cuts" user "Board Geometry/Outline")
		(27 "Margin" user)
		(31 "F.CrtYd" user "Package Geometry/Place Bound Top")
		(29 "B.CrtYd" user "Package Geometry/Place Bound Bottom")
		(35 "F.Fab" user "Ref Des/Assembly Top")
		(33 "B.Fab" user "Ref Des/Assembly Bottom")
	)
	(footprint ""
		(layer "B.Cu")
		(at 44.99991 -211.009992)
		(property "Reference" "J2"
			(at 4.384802 -5.317744 0)
			(unlocked yes)
			(layer "B.SilkS")
			(effects
				(font
					(size 0.7874 0.5842)
					(thickness 0.1524)
				)
				(justify left mirror)
			)
		)
		(property "Value" ""
			(at 0 0 0)
			(layer "B.Fab")
			(effects
				(font
					(size 1.27 1.27)
				)
				(justify mirror)
			)
		)
		(duplicate_pad_numbers_are_jumpers no)
		(fp_line
			(start -6.35 -4.52501)
			(end 4.350004 -4.52501)
			(stroke
				(width 0.1524)
				(type default)
			)
			(layer "B.SilkS")
		)
		(fp_line
			(start -6.35 18.524982)
			(end -6.35 -4.52501)
			(stroke
				(width 0.1524)
				(type default)
			)
			(layer "B.SilkS")
		)
		(fp_line
			(start -3.24993 -1.42494)
			(end -1.96977 -1.42494)
			(stroke
				(width 0.1524)
				(type default)
			)
			(layer "B.SilkS")
		)
		(fp_line
			(start -3.24993 15.424912)
			(end -3.24993 -1.42494)
			(stroke
				(width 0.1524)
				(type default)
			)
			(layer "B.SilkS")
		)
		(fp_line
			(start -0.029972 -1.42494)
			(end 1.249934 -1.42494)
			(stroke
				(width 0.1524)
				(type default)
			)
			(layer "B.SilkS")
		)
		(fp_line
			(start 1.249934 -1.42494)
			(end 1.249934 5.799836)
			(stroke
				(width 0.1524)
				(type default)
			)
			(layer "B.SilkS")
		)
		(fp_line
			(start 1.249934 5.799836)
			(end 4.350004 5.799836)
			(stroke
				(width 0.1524)
				(type default)
			)
			(layer "B.SilkS")
		)
		(fp_line
			(start 1.249934 8.200136)
			(end 1.249934 15.424912)
			(stroke
				(width 0.1524)
				(type default)
			)
			(layer "B.SilkS")
		)
		(fp_line
			(start 1.249934 8.200136)
			(end 4.350004 8.200136)
			(stroke
				(width 0.1524)
				(type default)
			)
			(layer "B.SilkS")
		)
		(fp_line
			(start 1.249934 15.424912)
			(end -3.24993 15.424912)
			(stroke
				(width 0.1524)
				(type default)
			)
			(layer "B.SilkS")
		)
		(fp_line
			(start 4.350004 -4.52501)
			(end 4.350004 18.524982)
			(stroke
				(width 0.1524)
				(type default)
			)
			(layer "B.SilkS")
		)
		(fp_line
			(start 4.350004 18.524982)
			(end -6.35 18.524982)
			(stroke
				(width 0.1524)
				(type default)
			)
			(layer "B.SilkS")
		)
		(fp_poly
			(pts
				(xy 5.527802 -0.508) (xy 5.527802 0.508) (xy 4.511802 0)
			)
			(stroke
				(width 0)
				(type default)
			)
			(fill yes)
			(layer "B.SilkS")
		)
		(fp_line
			(start -6.35 -4.52501)
			(end 4.350004 -4.52501)
			(stroke
				(width 0.1)
				(type default)
			)
			(layer "B.Fab")
		)
		(fp_line
			(start -6.35 18.524982)
			(end -6.35 -4.52501)
			(stroke
				(width 0.1)
				(type default)
			)
			(layer "B.Fab")
		)
		(fp_line
			(start 4.350004 -4.52501)
			(end 4.350004 18.524982)
			(stroke
				(width 0.1)
				(type default)
			)
			(layer "B.Fab")
		)
		(fp_line
			(start 4.350004 18.524982)
			(end -6.35 18.524982)
			(stroke
				(width 0.1)
				(type default)
			)
			(layer "B.Fab")
		)
		(fp_poly
			(pts
				(xy 5.527802 -0.508) (xy 5.527802 0.508) (xy 4.511802 0)
			)
			(stroke
				(width 0)
				(type default)
			)
			(fill yes)
			(layer "B.Fab")
		)
		(pad "" np_thru_hole circle
			(at -0.999998 -1.89992 270)
			(size 1.4986 1.4986)
			(drill 1.4986)
			(layers "*.Cu" "*.Mask")
			(clearance 0.381)
			(thermal_gap 0.381)
		)
		(pad "1" thru_hole rect
			(at 0 0 270)
			(size 1.3716 1.3716)
			(drill 0.9652)
			(layers "*.Cu" "*.Mask")
			(remove_unused_layers no)
			(net "FAN_1_TACH_IL_D")
			(clearance 0.0508)
			(padstack
				(mode front_inner_back)
				(layer "Inner"
					(shape circle)
					(size 1.3716 1.3716)
					(clearance 0.0508)
				)
				(layer "B.Cu"
					(shape rect)
					(size 1.3716 1.3716)
					(thermal_gap 0.0508)
					(clearance 0.0508)
				)
			)
		)
		(pad "2" thru_hole circle
			(at -1.999996 0 270)
			(size 1.3716 1.3716)
			(drill 0.9652)
			(layers "*.Cu" "*.Mask")
			(remove_unused_layers no)
			(net "FAN_1_PWM_OL_R")
			(clearance 0.0508)
			(thermal_gap 0.0508)
		)
		(pad "3" thru_hole circle
			(at 0 1.999996 270)
			(size 1.3716 1.3716)
			(drill 0.9652)
			(layers "*.Cu" "*.Mask")
			(remove_unused_layers no)
			(net "FAN_1_PWM_IL_R")
			(clearance 0.0508)
			(thermal_gap 0.0508)
		)
		(pad "4" thru_hole circle
			(at -1.999996 1.999996 270)
			(size 1.3716 1.3716)
			(drill 0.9652)
			(layers "*.Cu" "*.Mask")
			(remove_unused_layers no)
			(net "FAN_1_PRESENT_R_N")
			(clearance 0.0508)
			(thermal_gap 0.0508)
		)
		(pad "5" thru_hole circle
			(at 0 3.999992 270)
			(size 1.3716 1.3716)
			(drill 0.9652)
			(layers "*.Cu" "*.Mask")
			(remove_unused_layers no)
			(net "P12V_LED_R1_FAN1")
			(clearance 0.0508)
			(thermal_gap 0.0508)
		)
		(pad "6" thru_hole circle
			(at -1.999996 3.999992 270)
			(size 1.3716 1.3716)
			(drill 0.9652)
			(layers "*.Cu" "*.Mask")
			(remove_unused_layers no)
			(net "SMB_FAN1_SCL_R")
			(clearance 0.0508)
			(thermal_gap 0.0508)
		)
		(pad "7" thru_hole circle
			(at 0 5.999988 270)
			(size 1.3716 1.3716)
			(drill 0.9652)
			(layers "*.Cu" "*.Mask")
			(remove_unused_layers no)
			(net "SMB_FAN1_SDA_R")
			(clearance 0.0508)
			(thermal_gap 0.0508)
		)
		(pad "8" thru_hole circle
			(at -1.999996 5.999988 270)
			(size 1.3716 1.3716)
			(drill 0.9652)
			(layers "*.Cu" "*.Mask")
			(remove_unused_layers no)
			(net "GND")
			(clearance 0.0508)
			(thermal_gap 0.0508)
		)
		(pad "9" thru_hole circle
			(at 0 7.999984 270)
			(size 1.3716 1.3716)
			(drill 0.9652)
			(layers "*.Cu" "*.Mask")
			(remove_unused_layers no)
			(net "GND")
			(clearance 0.0508)
			(thermal_gap 0.0508)
		)
		(pad "10" thru_hole circle
			(at -1.999996 7.999984 270)
			(size 1.3716 1.3716)
			(drill 0.9652)
			(layers "*.Cu" "*.Mask")
			(remove_unused_layers no)
			(net "P52V_FAN_1")
			(clearance 0.0508)
			(thermal_gap 0.0508)
		)
		(pad "11" thru_hole circle
			(at 0 9.99998 270)
			(size 1.3716 1.3716)
			(drill 0.9652)
			(layers "*.Cu" "*.Mask")
			(remove_unused_layers no)
			(net "P52V_FAN_1")
			(clearance 0.0508)
			(thermal_gap 0.0508)
		)
		(pad "12" thru_hole circle
			(at -1.999996 9.99998 270)
			(size 1.3716 1.3716)
			(drill 0.9652)
			(layers "*.Cu" "*.Mask")
			(remove_unused_layers no)
			(net "FAN_1_FAIL_R_LED_N")
			(clearance 0.0508)
			(thermal_gap 0.0508)
		)
		(pad "13" thru_hole circle
			(at 0 11.999976 270)
			(size 1.3716 1.3716)
			(drill 0.9652)
			(layers "*.Cu" "*.Mask")
			(remove_unused_layers no)
			(net "FAN_1_TACH_OL_D")
			(clearance 0.0508)
			(thermal_gap 0.0508)
		)
		(pad "14" thru_hole circle
			(at -1.999996 11.999976 270)
			(size 1.3716 1.3716)
			(drill 0.9652)
			(layers "*.Cu" "*.Mask")
			(remove_unused_layers no)
			(net "FAN_1_OK_R_LED_N")
			(clearance 0.0508)
			(thermal_gap 0.0508)
		)
		(pad "15" thru_hole circle
			(at 0 13.999972 270)
			(size 1.3716 1.3716)
			(drill 0.9652)
			(layers "*.Cu" "*.Mask")
			(remove_unused_layers no)
			(net "Net_615")
			(clearance 0.0508)
			(thermal_gap 0.0508)
		)
		(pad "16" thru_hole circle
			(at -1.999996 13.999972 270)
			(size 1.3716 1.3716)
			(drill 0.9652)
			(layers "*.Cu" "*.Mask")
			(remove_unused_layers no)
			(net "Net_614")
			(clearance 0.0508)
			(thermal_gap 0.0508)
		)
		(zone
			(layers "F.Cu" "B.Cu" "In1.Cu" "In2.Cu" "In3.Cu" "In4.Cu")
			(hatch none 0.5)
			(connect_pads
				(clearance 0)
			)
			(min_thickness 0.25)
			(keepout
				(tracks not_allowed)
				(vias allowed)
				(pads allowed)
				(copperpour not_allowed)
				(footprints allowed)
			)
			(placement
				(enabled no)
				(sheetname "")
			)
			(fill
				(thermal_gap 0.5)
				(thermal_bridge_width 0.5)
				(island_removal_mode 0)
			)
			(polygon
				(pts
					(arc
						(start 45.257212 -212.909912)
						(mid 42.742612 -212.909912)
						(end 45.257212 -212.909912)
					)
				)
			)
		)
	)
)
